# Honey Badger  FCB_4Layer_Stackup.xlsx — Wiwynn (pcb-stackup)
|  |  |  |  |  |  |  |  |  | Single Ended Type(mil) |  |
|  |  |  |  |  |  |  |  | Imp | 50 |  |
|  |  |  |  |  |  |  |  | Variation | Outer ±5Ω |  |
|  |  |  |  |  |  |  |  | Bus | MISC. |  |
|  |  |  |  |  |  |  |  | Type | SE |  |
| Layer |  |  | Thickness |  | Er |  | Df(1G) | Layers | 1,4 |  |
|  |  | Cu oz | Wiwynn | Vender | Wiwynn | Vender |  |  | Wiwynn | Vender |
|  | Mask |  | 0.5 |  | 4.2 |  |  |  | Width | Width |
| Top | Signal | 0.5 oz + plating | 1.7 |  |  |  |  | S1 | 5.5 |  |
|  | Prepreg |  | 3.5 |  | 3.7 |  |  |  |  |  |
| L2 | PWR/GND | 2 oz | 2.6 |  |  |  |  | G2 |  |  |
|  | Core |  | 47 |  | 4.2 |  |  |  |  |  |
| L3 | GND/PWR | 2 oz | 2.6 |  |  |  |  | P3 |  |  |
|  | Prepreg |  | 3.5 |  | 3.7 |  |  |  |  |  |
| Bottom | Signal | 0.5 oz + plating | 1.7 |  |  |  |  | S4 | 5.5 |  |
|  | Mask |  | 0.5 |  | 4.2 |  |  |  |  |  |
| Thickness requirement: 1.6±10% mm |  | mil | 63.6 |  |  |  |  |  |  |  |
|  |  | mm | 1.6154432308864619 |  |  |  |  |  |  |  |
| Note: | 1. Unit is mil |  |  |  |  |  |  |  |  |  |
|  | 2. The total thickness includes trace and solder mask |  |  |  |  |  |  |  |  |  |
|  | 3. Minimum via hole copper thickness is 1.0 mil |  |  |  |  |  |  |  |  |  |
|  | 4. Minimum surface copper thickness 1.5 mil |  |  |  |  |  |  |  |  |  |
